# T6G (Grand Teton) — schematic netlist excerpt (pin names and nets, part order shuffled) for the footprints in the layout excerpt that follows; sources: Cadence DE-HDL packaged netlist, KiCad conversion of 04192023_DAF0TMB3IC0_F0TG_MB_C_brd_V02_OCP.brd

PR8006  Q_RES  0 5% CHIP  pkg 0402LF  page 193 : A = SVID_PVDDCR_CPU0_P0_SVD_R ; B = SVID_PVDDCR_CPU0_P0_SVD_R1
R104  Q_RES  1K 1% EMPTY  pkg 0402LF  page 99 : A = P3V3 ; B = PWRGD_CHB_CPU1_DIMM

(kicad_pcb
	(version 20260206)
	(generator "pcbnew")
	(generator_version "10.0")
	(general
		(thickness 1.6)
		(legacy_teardrops no)
	)
	(paper "A4")
	(title_block
		(title "04192023_DAF0TMB3IC0_F0TG_MB_C_brd_V02_OCP.brd")
		(comment 1 "Grand Teton / footprints 5842-5843 of 8354")
	)
	(layers
		(0 "F.Cu" signal "TOP")
		(4 "In1.Cu" signal "GND")
		(6 "In2.Cu" signal "IN1")
		(8 "In3.Cu" signal "GND1")
		(10 "In4.Cu" signal "IN2")
		(12 "In5.Cu" signal "GND2")
		(14 "In6.Cu" signal "IN3")
		(16 "In7.Cu" signal "GND3")
		(18 "In8.Cu" signal "VCC")
		(20 "In9.Cu" signal "VCC1")
		(22 "In10.Cu" signal "GND4")
		(24 "In11.Cu" signal "IN4")
		(26 "In12.Cu" signal "GND5")
		(28 "In13.Cu" signal "IN5")
		(30 "In14.Cu" signal "GND6")
		(32 "In15.Cu" signal "IN6")
		(34 "In16.Cu" signal "GND7")
		(2 "B.Cu" signal "BOTTOM")
		(9 "F.Adhes" user "F.Adhesive")
		(11 "B.Adhes" user "B.Adhesive")
		(13 "F.Paste" user "Package Geometry/Pastemask Top")
		(15 "B.Paste" user "Package Geometry/Pastemask Bottom")
		(5 "F.SilkS" user "Ref Des/Silkscreen Top")
		(7 "B.SilkS" user "Ref Des/Silkscreen Bottom")
		(1 "F.Mask" user "Board Geometry/Soldermask Top")
		(3 "B.Mask" user "Board Geometry/Soldermask Bottom")
		(17 "Dwgs.User" user "User.Drawings")
		(19 "Cmts.User" user "User.Comments")
		(21 "Eco1.User" user "User.Eco1")
		(23 "Eco2.User" user "User.Eco2")
		(25 "Edge.Cuts" user "Board Geometry/Outline")
		(27 "Margin" user)
		(31 "F.CrtYd" user "Package Geometry/Place Bound Top")
		(29 "B.CrtYd" user "Package Geometry/Place Bound Bottom")
		(35 "F.Fab" user "Ref Des/Assembly Top")
		(33 "B.Fab" user "Ref Des/Assembly Bottom")
	)
	(footprint ""
		(layer "B.Cu")
		(at 48.555148 -193.996564)
		(property "Reference" "R104"
			(at 0 0 0)
			(layer "B.SilkS")
			(hide yes)
			(effects
				(font
					(size 1.27 1.27)
				)
				(justify mirror)
			)
		)
		(property "Value" ""
			(at 0 0 0)
			(layer "B.Fab")
			(effects
				(font
					(size 1.27 1.27)
				)
				(justify mirror)
			)
		)
		(duplicate_pad_numbers_are_jumpers no)
		(fp_line
			(start -0.7874 -0.4064)
			(end -0.7874 0.4064)
			(stroke
				(width 0.1524)
				(type default)
			)
			(layer "B.SilkS")
		)
		(fp_line
			(start -0.7874 0.4064)
			(end 0.7874 0.4064)
			(stroke
				(width 0.1524)
				(type default)
			)
			(layer "B.SilkS")
		)
		(fp_line
			(start 0.7874 -0.4064)
			(end -0.7874 -0.4064)
			(stroke
				(width 0.1524)
				(type default)
			)
			(layer "B.SilkS")
		)
		(fp_line
			(start 0.7874 0.4064)
			(end 0.7874 -0.4064)
			(stroke
				(width 0.1524)
				(type default)
			)
			(layer "B.SilkS")
		)
		(fp_line
			(start -0.67945 -0.3048)
			(end -0.67945 0.3048)
			(stroke
				(width 0.1)
				(type default)
			)
			(layer "B.Fab")
		)
		(fp_line
			(start -0.67945 0.3048)
			(end -0.120396 0.3048)
			(stroke
				(width 0.1)
				(type default)
			)
			(layer "B.Fab")
		)
		(fp_line
			(start -0.12065 -0.3048)
			(end -0.67945 -0.3048)
			(stroke
				(width 0.1)
				(type default)
			)
			(layer "B.Fab")
		)
		(fp_line
			(start -0.12065 -0.2794)
			(end -0.12065 -0.3048)
			(stroke
				(width 0.1)
				(type default)
			)
			(layer "B.Fab")
		)
		(fp_line
			(start -0.120396 0.2794)
			(end 0.12065 0.2794)
			(stroke
				(width 0.1)
				(type default)
			)
			(layer "B.Fab")
		)
		(fp_line
			(start -0.120396 0.3048)
			(end -0.120396 0.2794)
			(stroke
				(width 0.1)
				(type default)
			)
			(layer "B.Fab")
		)
		(fp_line
			(start 0.12065 -0.305054)
			(end 0.12065 -0.2794)
			(stroke
				(width 0.1)
				(type default)
			)
			(layer "B.Fab")
		)
		(fp_line
			(start 0.12065 -0.2794)
			(end -0.12065 -0.2794)
			(stroke
				(width 0.1)
				(type default)
			)
			(layer "B.Fab")
		)
		(fp_line
			(start 0.12065 0.2794)
			(end 0.12065 0.3048)
			(stroke
				(width 0.1)
				(type default)
			)
			(layer "B.Fab")
		)
		(fp_line
			(start 0.12065 0.3048)
			(end 0.67945 0.3048)
			(stroke
				(width 0.1)
				(type default)
			)
			(layer "B.Fab")
		)
		(fp_line
			(start 0.67945 -0.305054)
			(end 0.12065 -0.305054)
			(stroke
				(width 0.1)
				(type default)
			)
			(layer "B.Fab")
		)
		(fp_line
			(start 0.67945 0.3048)
			(end 0.67945 -0.305054)
			(stroke
				(width 0.1)
				(type default)
			)
			(layer "B.Fab")
		)
		(pad "1" smd circle
			(at 0.40005 0 180)
			(size 0 0)
			(layers "B.Cu" "B.Mask" "B.Paste")
			(net "P3V3")
		)
		(pad "2" smd circle
			(at -0.40005 0 180)
			(size 0 0)
			(layers "B.Cu" "B.Mask" "B.Paste")
			(net "PWRGD_CHB_CPU1_DIMM")
		)
	)
	(footprint ""
		(layer "B.Cu")
		(at 372.937278 -144.520158 180)
		(property "Reference" "PR8006"
			(at 0 0 0)
			(layer "B.SilkS")
			(hide yes)
			(effects
				(font
					(size 1.27 1.27)
				)
				(justify mirror)
			)
		)
		(property "Value" ""
			(at 0 0 0)
			(layer "B.Fab")
			(effects
				(font
					(size 1.27 1.27)
				)
				(justify mirror)
			)
		)
		(duplicate_pad_numbers_are_jumpers no)
		(fp_line
			(start 0.7874 0.4064)
			(end 0.7874 -0.4064)
			(stroke
				(width 0.1524)
				(type default)
			)
			(layer "B.SilkS")
		)
		(fp_line
			(start 0.7874 -0.4064)
			(end -0.7874 -0.4064)
			(stroke
				(width 0.1524)
				(type default)
			)
			(layer "B.SilkS")
		)
		(fp_line
			(start -0.7874 0.4064)
			(end 0.7874 0.4064)
			(stroke
				(width 0.1524)
				(type default)
			)
			(layer "B.SilkS")
		)
		(fp_line
			(start -0.7874 -0.4064)
			(end -0.7874 0.4064)
			(stroke
				(width 0.1524)
				(type default)
			)
			(layer "B.SilkS")
		)
		(fp_line
			(start 0.67945 0.3048)
			(end 0.67945 -0.305054)
			(stroke
				(width 0.1)
				(type default)
			)
			(layer "B.Fab")
		)
		(fp_line
			(start 0.67945 -0.305054)
			(end 0.12065 -0.305054)
			(stroke
				(width 0.1)
				(type default)
			)
			(layer "B.Fab")
		)
		(fp_line
			(start 0.12065 0.3048)
			(end 0.67945 0.3048)
			(stroke
				(width 0.1)
				(type default)
			)
			(layer "B.Fab")
		)
		(fp_line
			(start 0.12065 0.2794)
			(end 0.12065 0.3048)
			(stroke
				(width 0.1)
				(type default)
			)
			(layer "B.Fab")
		)
		(fp_line
			(start 0.12065 -0.2794)
			(end -0.12065 -0.2794)
			(stroke
				(width 0.1)
				(type default)
			)
			(layer "B.Fab")
		)
		(fp_line
			(start 0.12065 -0.305054)
			(end 0.12065 -0.2794)
			(stroke
				(width 0.1)
				(type default)
			)
			(layer "B.Fab")
		)
		(fp_line
			(start -0.120396 0.3048)
			(end -0.120396 0.2794)
			(stroke
				(width 0.1)
				(type default)
			)
			(layer "B.Fab")
		)
		(fp_line
			(start -0.120396 0.2794)
			(end 0.12065 0.2794)
			(stroke
				(width 0.1)
				(type default)
			)
			(layer "B.Fab")
		)
		(fp_line
			(start -0.12065 -0.2794)
			(end -0.12065 -0.3048)
			(stroke
				(width 0.1)
				(type default)
			)
			(layer "B.Fab")
		)
		(fp_line
			(start -0.12065 -0.3048)
			(end -0.67945 -0.3048)
			(stroke
				(width 0.1)
				(type default)
			)
			(layer "B.Fab")
		)
		(fp_line
			(start -0.67945 0.3048)
			(end -0.120396 0.3048)
			(stroke
				(width 0.1)
				(type default)
			)
			(layer "B.Fab")
		)
		(fp_line
			(start -0.67945 -0.3048)
			(end -0.67945 0.3048)
			(stroke
				(width 0.1)
				(type default)
			)
			(layer "B.Fab")
		)
		(pad "1" smd circle
			(at 0.40005 0)
			(size 0 0)
			(layers "B.Cu" "B.Mask" "B.Paste")
			(net "SVID_PVDDCR_CPU0_P0_SVD_R")
		)
		(pad "2" smd circle
			(at -0.40005 0)
			(size 0 0)
			(layers "B.Cu" "B.Mask" "B.Paste")
			(net "SVID_PVDDCR_CPU0_P0_SVD_R1")
		)
	)
)
